FILE_TYPE=LIBRARY_PARTS;
primitive '9FGL0251DKILFT';
  pin
    'XIN||CLKIN_25':
      PIN_NUMBER='(1)';
      INPUT_LOAD='(-0.01,0.01)';
    'X2':
      PIN_NUMBER='(2)';
      OUTPUT_LOAD='(1.0,-1.0)';
    'VDDXTAL3.3':
      PIN_NUMBER='(3)';
      PINUSE='POWER';
      NO_LOAD_CHECK='Both';
      NO_IO_CHECK='Both';
      NO_ASSERT_CHECK='TRUE';
      NO_DIR_CHECK='TRUE';
      ALLOW_CONNECT='TRUE';
    'VSADR||REF3.3':
      PIN_NUMBER='(4)';
      BIDIRECTIONAL='TRUE';
      INPUT_LOAD='(-0.01,0.01)';
      OUTPUT_LOAD='(1.0,-1.0)';
    'GNDREF':
      PIN_NUMBER='(5)';
      PINUSE='POWER';
      NO_LOAD_CHECK='Both';
      NO_IO_CHECK='Both';
      NO_ASSERT_CHECK='TRUE';
      NO_DIR_CHECK='TRUE';
      ALLOW_CONNECT='TRUE';
    'GNDDIG':
      PIN_NUMBER='(6)';
      PINUSE='POWER';
      NO_LOAD_CHECK='Both';
      NO_IO_CHECK='Both';
      NO_ASSERT_CHECK='TRUE';
      NO_DIR_CHECK='TRUE';
      ALLOW_CONNECT='TRUE';
    'VDDDIG3.3':
      PIN_NUMBER='(7)';
      PINUSE='POWER';
      NO_LOAD_CHECK='Both';
      NO_IO_CHECK='Both';
      NO_ASSERT_CHECK='TRUE';
      NO_DIR_CHECK='TRUE';
      ALLOW_CONNECT='TRUE';
    'SCLK_3.3':
      PIN_NUMBER='(8)';
      INPUT_LOAD='(-0.01,0.01)';
    'SDATA_3.3':
      PIN_NUMBER='(9)';
      BIDIRECTIONAL='TRUE';
      INPUT_LOAD='(-0.01,0.01)';
      OUTPUT_LOAD='(1.0,-1.0)';
    'GND_10':
      PIN_NUMBER='(10)';
      PINUSE='POWER';
      NO_LOAD_CHECK='Both';
      NO_IO_CHECK='Both';
      NO_ASSERT_CHECK='TRUE';
      NO_DIR_CHECK='TRUE';
      ALLOW_CONNECT='TRUE';
    'VDD3.3_11':
      PIN_NUMBER='(11)';
      PINUSE='POWER';
      NO_LOAD_CHECK='Both';
      NO_IO_CHECK='Both';
      NO_ASSERT_CHECK='TRUE';
      NO_DIR_CHECK='TRUE';
      ALLOW_CONNECT='TRUE';
    'VOE0#':
      PIN_NUMBER='(12)';
      INPUT_LOAD='(-0.01,0.01)';
    'DIF0':
      PIN_NUMBER='(13)';
      OUTPUT_LOAD='(1.0,-1.0)';
    'DIF0#':
      PIN_NUMBER='(14)';
      OUTPUT_LOAD='(1.0,-1.0)';
    'GNDA':
      PIN_NUMBER='(15)';
      PINUSE='POWER';
      NO_LOAD_CHECK='Both';
      NO_IO_CHECK='Both';
      NO_ASSERT_CHECK='TRUE';
      NO_DIR_CHECK='TRUE';
      ALLOW_CONNECT='TRUE';
    'VDDA3.3':
      PIN_NUMBER='(16)';
      PINUSE='POWER';
      NO_LOAD_CHECK='Both';
      NO_IO_CHECK='Both';
      NO_ASSERT_CHECK='TRUE';
      NO_DIR_CHECK='TRUE';
      ALLOW_CONNECT='TRUE';
    'DIF1':
      PIN_NUMBER='(17)';
      OUTPUT_LOAD='(1.0,-1.0)';
    'DIF1#':
      PIN_NUMBER='(18)';
      OUTPUT_LOAD='(1.0,-1.0)';
    'VOE1#':
      PIN_NUMBER='(19)';
      INPUT_LOAD='(-0.01,0.01)';
    'VDD3.3_20':
      PIN_NUMBER='(20)';
      PINUSE='POWER';
      NO_LOAD_CHECK='Both';
      NO_IO_CHECK='Both';
      NO_ASSERT_CHECK='TRUE';
      NO_DIR_CHECK='TRUE';
      ALLOW_CONNECT='TRUE';
    'GND_21':
      PIN_NUMBER='(21)';
      PINUSE='POWER';
      NO_LOAD_CHECK='Both';
      NO_IO_CHECK='Both';
      NO_ASSERT_CHECK='TRUE';
      NO_DIR_CHECK='TRUE';
      ALLOW_CONNECT='TRUE';
    '^CKPWRGD_PD#':
      PIN_NUMBER='(22)';
      INPUT_LOAD='(-0.01,0.01)';
    '^VSS_EN_TRI':
      PIN_NUMBER='(23)';
      INPUT_LOAD='(-0.01,0.01)';
    'GNDXTAL':
      PIN_NUMBER='(24)';
      PINUSE='POWER';
      NO_LOAD_CHECK='Both';
      NO_IO_CHECK='Both';
      NO_ASSERT_CHECK='TRUE';
      NO_DIR_CHECK='TRUE';
      ALLOW_CONNECT='TRUE';
    'TH_GND':
      PIN_NUMBER='(25)';
      PINUSE='POWER';
      NO_LOAD_CHECK='Both';
      NO_IO_CHECK='Both';
      NO_ASSERT_CHECK='TRUE';
      NO_DIR_CHECK='TRUE';
      ALLOW_CONNECT='TRUE';
  end_pin;
  body
    PART_NAME='9FGL0251DKILFT';
    BODY_NAME='9FGL0251DKILFT';
    PHYS_DES_PREFIX='U';
    CLASS='IC';
  end_body;
end_primitive;

END.
